# S9S_MB_2U (Grand Teton) — schematic netlist excerpt (pin names and nets, part order shuffled) for the footprints in the layout excerpt that follows; sources: Cadence DE-HDL packaged netlist, KiCad conversion of 03242023_DA0F0TMBIJ0_F0T_Motherboard_J_brd_V01_OCP.brd

C317  Q_CAP  47UF 4V 20% X6S  pkg C0805  page 78 : A = PVCCIN_CPU1 ; B = GND
C1922  Q_CAP  22UF 6.3V 20% X6S  pkg C0603  page 190 : A = P3V3_M2_0 ; B = GND
R3163  Q_RES  4.7K 1% EMPTY  pkg 0402LF  page 159 : A = OCP_V3_2_ID0 ; B = GND

(kicad_pcb
	(version 20260206)
	(generator "pcbnew")
	(generator_version "10.0")
	(general
		(thickness 1.6)
		(legacy_teardrops no)
	)
	(paper "A4")
	(title_block
		(title "03242023_DA0F0TMBIJ0_F0T_Motherboard_J_brd_V01_OCP.brd")
		(comment 1 "Grand Teton / footprints 5872-5874 of 6105")
	)
	(layers
		(0 "F.Cu" signal "TOP")
		(4 "In1.Cu" signal "GND")
		(6 "In2.Cu" signal "IN1")
		(8 "In3.Cu" signal "GND1")
		(10 "In4.Cu" signal "IN2")
		(12 "In5.Cu" signal "GND2")
		(14 "In6.Cu" signal "IN3")
		(16 "In7.Cu" signal "GND3")
		(18 "In8.Cu" signal "VCC")
		(20 "In9.Cu" signal "VCC1")
		(22 "In10.Cu" signal "GND4")
		(24 "In11.Cu" signal "IN4")
		(26 "In12.Cu" signal "GND5")
		(28 "In13.Cu" signal "IN5")
		(30 "In14.Cu" signal "GND6")
		(32 "In15.Cu" signal "IN6")
		(34 "In16.Cu" signal "GND7")
		(2 "B.Cu" signal "BOTTOM")
		(9 "F.Adhes" user "F.Adhesive")
		(11 "B.Adhes" user "B.Adhesive")
		(13 "F.Paste" user "Package Geometry/Pastemask Top")
		(15 "B.Paste" user "Package Geometry/Pastemask Bottom")
		(5 "F.SilkS" user "Ref Des/Silkscreen Top")
		(7 "B.SilkS" user "Ref Des/Silkscreen Bottom")
		(1 "F.Mask" user "Board Geometry/Soldermask Top")
		(3 "B.Mask" user "Board Geometry/Soldermask Bottom")
		(17 "Dwgs.User" user "User.Drawings")
		(19 "Cmts.User" user "User.Comments")
		(21 "Eco1.User" user "User.Eco1")
		(23 "Eco2.User" user "User.Eco2")
		(25 "Edge.Cuts" user "Board Geometry/Outline")
		(27 "Margin" user)
		(31 "F.CrtYd" user "Package Geometry/Place Bound Top")
		(29 "B.CrtYd" user "Package Geometry/Place Bound Bottom")
		(35 "F.Fab" user "Ref Des/Assembly Top")
		(33 "B.Fab" user "Ref Des/Assembly Bottom")
	)
	(footprint ""
		(layer "B.Cu")
		(at 170.12158 -50.107088 180)
		(property "Reference" "C1922"
			(at 0 0 0)
			(layer "B.SilkS")
			(hide yes)
			(effects
				(font
					(size 1.27 1.27)
				)
				(justify mirror)
			)
		)
		(property "Value" ""
			(at 0 0 0)
			(layer "B.Fab")
			(effects
				(font
					(size 1.27 1.27)
				)
				(justify mirror)
			)
		)
		(duplicate_pad_numbers_are_jumpers no)
		(fp_line
			(start 1.2954 0.5842)
			(end 1.2954 -0.5842)
			(stroke
				(width 0.1524)
				(type default)
			)
			(layer "B.SilkS")
		)
		(fp_line
			(start 1.2954 -0.5842)
			(end -1.2954 -0.5842)
			(stroke
				(width 0.1524)
				(type default)
			)
			(layer "B.SilkS")
		)
		(fp_line
			(start 0 -0.5842)
			(end 0 0.5842)
			(stroke
				(width 0.1524)
				(type default)
			)
			(layer "B.SilkS")
		)
		(fp_line
			(start -1.2954 0.5842)
			(end 1.2954 0.5842)
			(stroke
				(width 0.1524)
				(type default)
			)
			(layer "B.SilkS")
		)
		(fp_line
			(start -1.2954 -0.5842)
			(end -1.2954 0.5842)
			(stroke
				(width 0.1524)
				(type default)
			)
			(layer "B.SilkS")
		)
		(fp_line
			(start 1.1938 0.4064)
			(end 1.1938 -0.4064)
			(stroke
				(width 0.1)
				(type default)
			)
			(layer "B.Fab")
		)
		(fp_line
			(start 1.1938 -0.4064)
			(end 0.8636 -0.4064)
			(stroke
				(width 0.1)
				(type default)
			)
			(layer "B.Fab")
		)
		(fp_line
			(start 0.8636 0.4572)
			(end 0.8636 0.4064)
			(stroke
				(width 0.1)
				(type default)
			)
			(layer "B.Fab")
		)
		(fp_line
			(start 0.8636 0.4064)
			(end 1.1938 0.4064)
			(stroke
				(width 0.1)
				(type default)
			)
			(layer "B.Fab")
		)
		(fp_line
			(start 0.8636 -0.4064)
			(end 0.8636 -0.4572)
			(stroke
				(width 0.1)
				(type default)
			)
			(layer "B.Fab")
		)
		(fp_line
			(start 0.8636 -0.4572)
			(end -0.8636 -0.4572)
			(stroke
				(width 0.1)
				(type default)
			)
			(layer "B.Fab")
		)
		(fp_line
			(start -0.8636 0.4572)
			(end 0.8636 0.4572)
			(stroke
				(width 0.1)
				(type default)
			)
			(layer "B.Fab")
		)
		(fp_line
			(start -0.8636 0.4064)
			(end -0.8636 0.4572)
			(stroke
				(width 0.1)
				(type default)
			)
			(layer "B.Fab")
		)
		(fp_line
			(start -0.8636 -0.4064)
			(end -1.1938 -0.4064)
			(stroke
				(width 0.1)
				(type default)
			)
			(layer "B.Fab")
		)
		(fp_line
			(start -0.8636 -0.4572)
			(end -0.8636 -0.4064)
			(stroke
				(width 0.1)
				(type default)
			)
			(layer "B.Fab")
		)
		(fp_line
			(start -1.1938 0.4064)
			(end -0.8636 0.4064)
			(stroke
				(width 0.1)
				(type default)
			)
			(layer "B.Fab")
		)
		(fp_line
			(start -1.1938 -0.4064)
			(end -1.1938 0.4064)
			(stroke
				(width 0.1)
				(type default)
			)
			(layer "B.Fab")
		)
		(pad "1" smd rect
			(at 0.7366 0 90)
			(size 0.7112 0.8128)
			(layers "B.Cu" "B.Mask" "B.Paste")
			(net "P3V3_M2_0")
		)
		(pad "2" smd rect
			(at -0.7366 0 90)
			(size 0.7112 0.8128)
			(layers "B.Cu" "B.Mask" "B.Paste")
			(net "GND")
		)
	)
	(footprint ""
		(layer "B.Cu")
		(at 118.18112 -244.82044 -90)
		(property "Reference" "C317"
			(at 0 0 90)
			(layer "B.SilkS")
			(hide yes)
			(effects
				(font
					(size 1.27 1.27)
				)
				(justify mirror)
			)
		)
		(property "Value" ""
			(at 0 0 90)
			(layer "B.Fab")
			(effects
				(font
					(size 1.27 1.27)
				)
				(justify mirror)
			)
		)
		(duplicate_pad_numbers_are_jumpers no)
		(fp_line
			(start -1.524 0.762)
			(end 1.524 0.762)
			(stroke
				(width 0.1524)
				(type default)
			)
			(layer "B.SilkS")
		)
		(fp_line
			(start 1.524 0.762)
			(end 1.524 -0.762)
			(stroke
				(width 0.1524)
				(type default)
			)
			(layer "B.SilkS")
		)
		(fp_line
			(start -1.524 -0.762)
			(end -1.524 0.762)
			(stroke
				(width 0.1524)
				(type default)
			)
			(layer "B.SilkS")
		)
		(fp_line
			(start 1.524 -0.762)
			(end -1.524 -0.762)
			(stroke
				(width 0.1524)
				(type default)
			)
			(layer "B.SilkS")
		)
		(fp_line
			(start -1.1049 0.724916)
			(end -1.1049 -0.724916)
			(stroke
				(width 0.1)
				(type default)
			)
			(layer "B.Fab")
		)
		(fp_line
			(start 1.1049 0.724916)
			(end -1.1049 0.724916)
			(stroke
				(width 0.1)
				(type default)
			)
			(layer "B.Fab")
		)
		(fp_line
			(start -1.1049 -0.724916)
			(end 1.1049 -0.724916)
			(stroke
				(width 0.1)
				(type default)
			)
			(layer "B.Fab")
		)
		(fp_line
			(start 1.1049 -0.724916)
			(end 1.1049 0.724916)
			(stroke
				(width 0.1)
				(type default)
			)
			(layer "B.Fab")
		)
		(pad "1" smd rect
			(at 0.889 0 270)
			(size 1.016 1.27)
			(layers "B.Cu" "B.Mask" "B.Paste")
			(net "PVCCIN_CPU1")
		)
		(pad "2" smd rect
			(at -0.889 0 270)
			(size 1.016 1.27)
			(layers "B.Cu" "B.Mask" "B.Paste")
			(net "GND")
		)
	)
	(footprint ""
		(layer "B.Cu")
		(at 72.82688 -11.267948 90)
		(property "Reference" "R3163"
			(at 0 0 90)
			(layer "B.SilkS")
			(hide yes)
			(effects
				(font
					(size 1.27 1.27)
				)
				(justify mirror)
			)
		)
		(property "Value" ""
			(at 0 0 90)
			(layer "B.Fab")
			(effects
				(font
					(size 1.27 1.27)
				)
				(justify mirror)
			)
		)
		(duplicate_pad_numbers_are_jumpers no)
		(fp_line
			(start 0.7874 -0.4064)
			(end -0.7874 -0.4064)
			(stroke
				(width 0.1524)
				(type default)
			)
			(layer "B.SilkS")
		)
		(fp_line
			(start -0.7874 -0.4064)
			(end -0.7874 0.4064)
			(stroke
				(width 0.1524)
				(type default)
			)
			(layer "B.SilkS")
		)
		(fp_line
			(start 0.7874 0.4064)
			(end 0.7874 -0.4064)
			(stroke
				(width 0.1524)
				(type default)
			)
			(layer "B.SilkS")
		)
		(fp_line
			(start -0.7874 0.4064)
			(end 0.7874 0.4064)
			(stroke
				(width 0.1524)
				(type default)
			)
			(layer "B.SilkS")
		)
		(fp_line
			(start 0.67945 -0.305054)
			(end 0.12065 -0.305054)
			(stroke
				(width 0.1)
				(type default)
			)
			(layer "B.Fab")
		)
		(fp_line
			(start 0.12065 -0.305054)
			(end 0.12065 -0.2794)
			(stroke
				(width 0.1)
				(type default)
			)
			(layer "B.Fab")
		)
		(fp_line
			(start -0.12065 -0.3048)
			(end -0.67945 -0.3048)
			(stroke
				(width 0.1)
				(type default)
			)
			(layer "B.Fab")
		)
		(fp_line
			(start -0.67945 -0.3048)
			(end -0.67945 0.3048)
			(stroke
				(width 0.1)
				(type default)
			)
			(layer "B.Fab")
		)
		(fp_line
			(start 0.12065 -0.2794)
			(end -0.12065 -0.2794)
			(stroke
				(width 0.1)
				(type default)
			)
			(layer "B.Fab")
		)
		(fp_line
			(start -0.12065 -0.2794)
			(end -0.12065 -0.3048)
			(stroke
				(width 0.1)
				(type default)
			)
			(layer "B.Fab")
		)
		(fp_line
			(start 0.12065 0.2794)
			(end 0.12065 0.3048)
			(stroke
				(width 0.1)
				(type default)
			)
			(layer "B.Fab")
		)
		(fp_line
			(start -0.120396 0.2794)
			(end 0.12065 0.2794)
			(stroke
				(width 0.1)
				(type default)
			)
			(layer "B.Fab")
		)
		(fp_line
			(start 0.67945 0.3048)
			(end 0.67945 -0.305054)
			(stroke
				(width 0.1)
				(type default)
			)
			(layer "B.Fab")
		)
		(fp_line
			(start 0.12065 0.3048)
			(end 0.67945 0.3048)
			(stroke
				(width 0.1)
				(type default)
			)
			(layer "B.Fab")
		)
		(fp_line
			(start -0.120396 0.3048)
			(end -0.120396 0.2794)
			(stroke
				(width 0.1)
				(type default)
			)
			(layer "B.Fab")
		)
		(fp_line
			(start -0.67945 0.3048)
			(end -0.120396 0.3048)
			(stroke
				(width 0.1)
				(type default)
			)
			(layer "B.Fab")
		)
		(pad "1" smd circle
			(at 0.40005 0 270)
			(size 0 0)
			(layers "B.Cu" "B.Mask" "B.Paste")
			(net "OCP_V3_2_ID0")
		)
		(pad "2" smd circle
			(at -0.40005 0 270)
			(size 0 0)
			(layers "B.Cu" "B.Mask" "B.Paste")
			(net "GND")
		)
	)
)
